(kicad_pcb
	(version 20260206)
	(generator "pcbnew")
	(generator_version "10.0")
	(general
		(thickness 1.6)
		(legacy_teardrops no)
	)
	(paper "A4")
	(title_block
		(title "pdpb — Lightning_PDPB_BRD.brd")
		(comment 1 "Lightning (Wiwynn / Facebook NVMe JBOF) / footprints 269-275 of 1140")
	)
	(layers
		(0 "F.Cu" signal "TOP")
		(4 "In1.Cu" signal "L2GND")
		(6 "In2.Cu" signal "L3")
		(8 "In3.Cu" signal "L4VCC")
		(10 "In4.Cu" signal "L5VCC")
		(12 "In5.Cu" signal "L6")
		(14 "In6.Cu" signal "L7GND")
		(2 "B.Cu" signal "BOTTOM")
		(9 "F.Adhes" user "F.Adhesive")
		(11 "B.Adhes" user "B.Adhesive")
		(13 "F.Paste" user "Package Geometry/Pastemask Top")
		(15 "B.Paste" user "Package Geometry/Pastemask Bottom")
		(5 "F.SilkS" user "Ref Des/Silkscreen Top")
		(7 "B.SilkS" user "Ref Des/Silkscreen Bottom")
		(1 "F.Mask" user "Board Geometry/Soldermask Top")
		(3 "B.Mask" user "Board Geometry/Soldermask Bottom")
		(17 "Dwgs.User" user "User.Drawings")
		(19 "Cmts.User" user "User.Comments")
		(21 "Eco1.User" user "User.Eco1")
		(23 "Eco2.User" user "User.Eco2")
		(25 "Edge.Cuts" user "Board Geometry/Outline")
		(27 "Margin" user)
		(31 "F.CrtYd" user "Package Geometry/Place Bound Top")
		(29 "B.CrtYd" user "Package Geometry/Place Bound Bottom")
		(35 "F.Fab" user "Ref Des/Assembly Top")
		(33 "B.Fab" user "Ref Des/Assembly Bottom")
	)
	(footprint ""
		(layer "F.Cu")
		(at 22.733 -493.141 -90)
		(property "Reference" "U14"
			(at 0 0 270)
			(layer "F.SilkS")
			(hide yes)
			(effects
				(font
					(size 1.27 1.27)
				)
			)
		)
		(property "Value" "P2003EVG-GP"
			(at 0 -11.1252 270)
			(unlocked yes)
			(layer "F.Fab")
			(hide yes)
			(effects
				(font
					(size 1.016 1.016)
					(thickness 0.1524)
				)
			)
		)
		(property "Device Type" "SOIC8H79"
			(at 0 -12.6492 270)
			(unlocked yes)
			(layer "F.Fab")
			(hide yes)
			(effects
				(font
					(size 1.016 1.016)
					(thickness 0.1524)
				)
			)
		)
		(duplicate_pad_numbers_are_jumpers no)
		(fp_line
			(start -2.6162 3.429)
			(end -2.6162 1.4732)
			(stroke
				(width 0.4064)
				(type default)
			)
			(layer "F.SilkS")
		)
		(fp_line
			(start -2.7432 1.4224)
			(end 2.1336 1.4224)
			(stroke
				(width 0.1524)
				(type default)
			)
			(layer "F.SilkS")
		)
		(fp_line
			(start 2.1336 1.4224)
			(end 2.1336 -1.4224)
			(stroke
				(width 0.1524)
				(type default)
			)
			(layer "F.SilkS")
		)
		(fp_line
			(start -2.2352 0)
			(end -2.7432 0.508)
			(stroke
				(width 0.1524)
				(type default)
			)
			(layer "F.SilkS")
		)
		(fp_line
			(start -2.7432 -0.508)
			(end -2.2352 0)
			(stroke
				(width 0.1524)
				(type default)
			)
			(layer "F.SilkS")
		)
		(fp_line
			(start -2.7432 -1.4224)
			(end -2.7432 1.4224)
			(stroke
				(width 0.1524)
				(type default)
			)
			(layer "F.SilkS")
		)
		(fp_line
			(start 2.1336 -1.4224)
			(end -2.7432 -1.4224)
			(stroke
				(width 0.1524)
				(type default)
			)
			(layer "F.SilkS")
		)
		(fp_poly
			(pts
				(xy 2.2098 -1.4224) (xy 2.2098 1.4224) (xy -2.2225 1.4224) (xy -2.2225 -1.4224)
			)
			(stroke
				(width 0)
				(type default)
			)
			(fill yes)
			(layer "F.SilkS")
		)
		(fp_rect
			(start -2.4511 2.9972)
			(end 2.4511 -2.9972)
			(stroke
				(width 0)
				(type default)
			)
			(fill no)
			(layer "F.CrtYd")
		)
		(fp_poly
			(pts
				(xy -2.8194 3.6322) (xy -2.8194 -3.6322) (xy 2.8194 -3.6322) (xy 2.8194 -2.2987) (xy 2.4511 -2.2987)
				(xy 2.4511 -2.9972) (xy -2.4511 -2.9972) (xy -2.4511 2.9972) (xy 2.4511 2.9972) (xy 2.4511 -2.286)
				(xy 2.8194 -2.286) (xy 2.8194 3.6322)
			)
			(stroke
				(width 0)
				(type default)
			)
			(fill no)
			(layer "F.CrtYd")
		)
		(fp_rect
			(start -2.8194 3.6322)
			(end 2.8194 -3.6322)
			(stroke
				(width 0)
				(type default)
			)
			(fill no)
			(layer "F.Fab")
		)
		(pad "1" smd rect
			(at -1.905 2.54 270)
			(size 0.635 1.651)
			(layers "F.Cu" "F.Mask" "F.Paste")
			(net "P12V")
		)
		(pad "2" smd rect
			(at -0.635 2.54 270)
			(size 0.635 1.651)
			(layers "F.Cu" "F.Mask" "F.Paste")
			(net "P12V")
		)
		(pad "3" smd rect
			(at 0.635 2.54 270)
			(size 0.635 1.651)
			(layers "F.Cu" "F.Mask" "F.Paste")
			(net "P12V")
		)
		(pad "4" smd rect
			(at 1.905 2.54 270)
			(size 0.635 1.651)
			(layers "F.Cu" "F.Mask" "F.Paste")
			(net "SW_SSD5_N")
		)
		(pad "5" smd rect
			(at 1.905 -2.54 270)
			(size 0.635 1.651)
			(layers "F.Cu" "F.Mask" "F.Paste")
			(net "P12V_SSD5")
		)
		(pad "6" smd rect
			(at 0.635 -2.54 270)
			(size 0.635 1.651)
			(layers "F.Cu" "F.Mask" "F.Paste")
			(net "P12V_SSD5")
		)
		(pad "7" smd rect
			(at -0.635 -2.54 270)
			(size 0.635 1.651)
			(layers "F.Cu" "F.Mask" "F.Paste")
			(net "P12V_SSD5")
		)
		(pad "8" smd rect
			(at -1.905 -2.54 270)
			(size 0.635 1.651)
			(layers "F.Cu" "F.Mask" "F.Paste")
			(net "P12V_SSD5")
		)
	)
	(footprint ""
		(layer "F.Cu")
		(at 25.4 -134.112 180)
		(property "Reference" "PC1214"
			(at 0 0 180)
			(layer "F.SilkS")
			(hide yes)
			(effects
				(font
					(size 1.27 1.27)
				)
			)
		)
		(property "Value" "SCD1U25V3KX-GP"
			(at 0 -2.8194 180)
			(unlocked yes)
			(layer "F.Fab")
			(hide yes)
			(effects
				(font
					(size 1.016 1.016)
					(thickness 0.1524)
				)
			)
		)
		(property "Device Type" "C603H36"
			(at 0 -4.3434 180)
			(unlocked yes)
			(layer "F.Fab")
			(hide yes)
			(effects
				(font
					(size 1.016 1.016)
					(thickness 0.1524)
				)
			)
		)
		(duplicate_pad_numbers_are_jumpers no)
		(fp_line
			(start 0.508 0)
			(end -0.508 0)
			(stroke
				(width 0.2032)
				(type default)
			)
			(layer "F.SilkS")
		)
		(fp_rect
			(start -0.5842 1.3335)
			(end 0.5842 -1.3335)
			(stroke
				(width 0)
				(type default)
			)
			(fill no)
			(layer "F.CrtYd")
		)
		(fp_rect
			(start -0.5842 1.3335)
			(end 0.5842 -1.3335)
			(stroke
				(width 0)
				(type default)
			)
			(fill no)
			(layer "F.Fab")
		)
		(pad "1" smd custom
			(at 0 -0.762 180)
			(size 0.2159 0.2159)
			(layers "F.Cu" "F.Mask" "F.Paste")
			(net "P3V3")
			(options
				(clearance outline)
				(anchor circle)
			)
			(primitives
				(gr_poly
					(pts
						(arc
							(start -0.3302 -0.4318)
							(mid -0.402042 -0.402042)
							(end -0.4318 -0.3302)
						)
						(arc
							(start -0.4318 0.3302)
							(mid -0.402042 0.402042)
							(end -0.3302 0.4318)
						)
						(arc
							(start 0.3302 0.4318)
							(mid 0.402042 0.402042)
							(end 0.4318 0.3302)
						)
						(arc
							(start 0.4318 -0.3302)
							(mid 0.402042 -0.402042)
							(end 0.3302 -0.4318)
						)
					)
					(width 0)
					(fill yes)
				)
			)
		)
		(pad "2" smd custom
			(at 0 0.762 180)
			(size 0.2159 0.2159)
			(layers "F.Cu" "F.Mask" "F.Paste")
			(net "GND")
			(options
				(clearance outline)
				(anchor circle)
			)
			(primitives
				(gr_poly
					(pts
						(arc
							(start -0.3302 -0.4318)
							(mid -0.402042 -0.402042)
							(end -0.4318 -0.3302)
						)
						(arc
							(start -0.4318 0.3302)
							(mid -0.402042 0.402042)
							(end -0.3302 0.4318)
						)
						(arc
							(start 0.3302 0.4318)
							(mid 0.402042 0.402042)
							(end 0.4318 0.3302)
						)
						(arc
							(start 0.4318 -0.3302)
							(mid 0.402042 -0.402042)
							(end 0.3302 -0.4318)
						)
					)
					(width 0)
					(fill yes)
				)
			)
		)
	)
	(footprint ""
		(layer "F.Cu")
		(at 89.789 -317.246 -90)
		(property "Reference" "C9349"
			(at 0 0 270)
			(layer "F.SilkS")
			(hide yes)
			(effects
				(font
					(size 1.27 1.27)
				)
			)
		)
		(property "Value" "SC1KP50V2KX-1GP"
			(at 1.1811 -2.7051 270)
			(unlocked yes)
			(layer "F.Fab")
			(hide yes)
			(effects
				(font
					(size 1.016 1.016)
					(thickness 0.1524)
				)
			)
		)
		(property "Device Type" "C402H22"
			(at 1.1811 -4.2291 270)
			(unlocked yes)
			(layer "F.Fab")
			(hide yes)
			(effects
				(font
					(size 1.016 1.016)
					(thickness 0.1524)
				)
			)
		)
		(duplicate_pad_numbers_are_jumpers no)
		(fp_rect
			(start -0.4318 0.9525)
			(end 0.4318 -0.9525)
			(stroke
				(width 0)
				(type default)
			)
			(fill no)
			(layer "F.CrtYd")
		)
		(fp_rect
			(start -0.4318 0.9525)
			(end 0.4318 -0.9525)
			(stroke
				(width 0)
				(type default)
			)
			(fill no)
			(layer "F.Fab")
		)
		(pad "1" smd custom
			(at 0 -0.4445 270)
			(size 0.1524 0.1524)
			(layers "F.Cu" "F.Mask" "F.Paste")
			(net "SSD_PRSNT11")
			(options
				(clearance outline)
				(anchor circle)
			)
			(primitives
				(gr_poly
					(pts
						(arc
							(start 0.3048 -0.2032)
							(mid 0.275042 -0.275042)
							(end 0.2032 -0.3048)
						)
						(arc
							(start -0.2032 -0.3048)
							(mid -0.275042 -0.275042)
							(end -0.3048 -0.2032)
						)
						(arc
							(start -0.3048 0.2032)
							(mid -0.275042 0.275042)
							(end -0.2032 0.3048)
						)
						(arc
							(start 0.2032 0.3048)
							(mid 0.275042 0.275042)
							(end 0.3048 0.2032)
						)
					)
					(width 0)
					(fill yes)
				)
			)
		)
		(pad "2" smd custom
			(at 0 0.4445 270)
			(size 0.1524 0.1524)
			(layers "F.Cu" "F.Mask" "F.Paste")
			(net "GND")
			(options
				(clearance outline)
				(anchor circle)
			)
			(primitives
				(gr_poly
					(pts
						(arc
							(start 0.3048 -0.2032)
							(mid 0.275042 -0.275042)
							(end 0.2032 -0.3048)
						)
						(arc
							(start -0.2032 -0.3048)
							(mid -0.275042 -0.275042)
							(end -0.3048 -0.2032)
						)
						(arc
							(start -0.3048 0.2032)
							(mid -0.275042 0.275042)
							(end -0.2032 0.3048)
						)
						(arc
							(start 0.2032 0.3048)
							(mid 0.275042 0.275042)
							(end 0.3048 0.2032)
						)
					)
					(width 0)
					(fill yes)
				)
			)
		)
	)
	(footprint ""
		(layer "F.Cu")
		(at 222.123 -400.685 180)
		(property "Reference" "PC1235"
			(at 0 0 180)
			(layer "F.SilkS")
			(hide yes)
			(effects
				(font
					(size 1.27 1.27)
				)
			)
		)
		(property "Value" "SC22U25V6KX-GP-U"
			(at -2.860802 -5.279644 180)
			(unlocked yes)
			(layer "F.Fab")
			(hide yes)
			(effects
				(font
					(size 1.016 1.016)
					(thickness 0.1524)
				)
			)
		)
		(property "Device Type" "C1206-TO0D3H75"
			(at -2.860802 -6.803644 180)
			(unlocked yes)
			(layer "F.Fab")
			(hide yes)
			(effects
				(font
					(size 1.016 1.016)
					(thickness 0.1524)
				)
			)
		)
		(duplicate_pad_numbers_are_jumpers no)
		(fp_line
			(start 1.3081 2.3749)
			(end -1.3081 2.3749)
			(stroke
				(width 0.1524)
				(type default)
			)
			(layer "F.SilkS")
		)
		(fp_line
			(start 1.3081 -2.3749)
			(end 1.3081 2.3749)
			(stroke
				(width 0.1524)
				(type default)
			)
			(layer "F.SilkS")
		)
		(fp_line
			(start -1.3081 2.3749)
			(end -1.3081 -2.3749)
			(stroke
				(width 0.1524)
				(type default)
			)
			(layer "F.SilkS")
		)
		(fp_line
			(start -1.3081 -2.3749)
			(end 1.3081 -2.3749)
			(stroke
				(width 0.1524)
				(type default)
			)
			(layer "F.SilkS")
		)
		(fp_rect
			(start -0.8001 1.6002)
			(end 0.8001 -1.6002)
			(stroke
				(width 0)
				(type default)
			)
			(fill no)
			(layer "F.CrtYd")
		)
		(fp_poly
			(pts
				(xy -1.5621 2.4511) (xy -1.5621 1.6002) (xy 0.8001 1.6002) (xy 0.8001 -1.6002) (xy -0.8001 -1.6002)
				(xy -0.8001 1.5875) (xy -1.5621 1.5875) (xy -1.5621 -2.4511) (xy 1.5621 -2.4511) (xy 1.5621 2.4511)
			)
			(stroke
				(width 0)
				(type default)
			)
			(fill no)
			(layer "F.CrtYd")
		)
		(fp_rect
			(start -1.5621 2.4511)
			(end 1.5621 -2.4511)
			(stroke
				(width 0)
				(type default)
			)
			(fill no)
			(layer "F.Fab")
		)
		(pad "1" smd rect
			(at 0 -1.392936 180)
			(size 2.1082 1.4478)
			(layers "F.Cu" "F.Mask" "F.Paste")
			(net "P12V_SSD1")
		)
		(pad "2" smd rect
			(at 0 1.392936 180)
			(size 2.1082 1.4478)
			(layers "F.Cu" "F.Mask" "F.Paste")
			(net "GND")
		)
	)
	(footprint ""
		(layer "F.Cu")
		(at 96.774 -317.246 -90)
		(property "Reference" "C9368"
			(at 0 0 270)
			(layer "F.SilkS")
			(hide yes)
			(effects
				(font
					(size 1.27 1.27)
				)
			)
		)
		(property "Value" "SC1KP50V2KX-1GP"
			(at 1.1811 -2.7051 270)
			(unlocked yes)
			(layer "F.Fab")
			(hide yes)
			(effects
				(font
					(size 1.016 1.016)
					(thickness 0.1524)
				)
			)
		)
		(property "Device Type" "C402H22"
			(at 1.1811 -4.2291 270)
			(unlocked yes)
			(layer "F.Fab")
			(hide yes)
			(effects
				(font
					(size 1.016 1.016)
					(thickness 0.1524)
				)
			)
		)
		(duplicate_pad_numbers_are_jumpers no)
		(fp_rect
			(start -0.4318 0.9525)
			(end 0.4318 -0.9525)
			(stroke
				(width 0)
				(type default)
			)
			(fill no)
			(layer "F.CrtYd")
		)
		(fp_rect
			(start -0.4318 0.9525)
			(end 0.4318 -0.9525)
			(stroke
				(width 0)
				(type default)
			)
			(fill no)
			(layer "F.Fab")
		)
		(pad "1" smd custom
			(at 0 -0.4445 270)
			(size 0.1524 0.1524)
			(layers "F.Cu" "F.Mask" "F.Paste")
			(net "SSD6_CLK0_OE_R_N")
			(options
				(clearance outline)
				(anchor circle)
			)
			(primitives
				(gr_poly
					(pts
						(arc
							(start 0.3048 -0.2032)
							(mid 0.275042 -0.275042)
							(end 0.2032 -0.3048)
						)
						(arc
							(start -0.2032 -0.3048)
							(mid -0.275042 -0.275042)
							(end -0.3048 -0.2032)
						)
						(arc
							(start -0.3048 0.2032)
							(mid -0.275042 0.275042)
							(end -0.2032 0.3048)
						)
						(arc
							(start 0.2032 0.3048)
							(mid 0.275042 0.275042)
							(end 0.3048 0.2032)
						)
					)
					(width 0)
					(fill yes)
				)
			)
		)
		(pad "2" smd custom
			(at 0 0.4445 270)
			(size 0.1524 0.1524)
			(layers "F.Cu" "F.Mask" "F.Paste")
			(net "GND")
			(options
				(clearance outline)
				(anchor circle)
			)
			(primitives
				(gr_poly
					(pts
						(arc
							(start 0.3048 -0.2032)
							(mid 0.275042 -0.275042)
							(end 0.2032 -0.3048)
						)
						(arc
							(start -0.2032 -0.3048)
							(mid -0.275042 -0.275042)
							(end -0.3048 -0.2032)
						)
						(arc
							(start -0.3048 0.2032)
							(mid -0.275042 0.275042)
							(end -0.2032 0.3048)
						)
						(arc
							(start 0.2032 0.3048)
							(mid 0.275042 0.275042)
							(end 0.3048 0.2032)
						)
					)
					(width 0)
					(fill yes)
				)
			)
		)
	)
	(footprint ""
		(layer "F.Cu")
		(at 19.547332 -56.002936 90)
		(property "Reference" "Q100"
			(at 0 0 90)
			(layer "F.SilkS")
			(hide yes)
			(effects
				(font
					(size 1.27 1.27)
				)
			)
		)
		(property "Value" "2N7002A-7-GP"
			(at 0.127 -8.9662 90)
			(unlocked yes)
			(layer "F.Fab")
			(hide yes)
			(effects
				(font
					(size 1.016 1.016)
					(thickness 0.1524)
				)
			)
		)
		(property "Device Type" "SOT23DGS2D4H48"
			(at 0.127 -10.4902 90)
			(unlocked yes)
			(layer "F.Fab")
			(hide yes)
			(effects
				(font
					(size 1.016 1.016)
					(thickness 0.1524)
				)
			)
		)
		(duplicate_pad_numbers_are_jumpers no)
		(fp_line
			(start 1.651 -1.778)
			(end -1.651 -1.778)
			(stroke
				(width 0.1524)
				(type default)
			)
			(layer "F.SilkS")
		)
		(fp_line
			(start -1.651 -1.778)
			(end -1.651 1.778)
			(stroke
				(width 0.1524)
				(type default)
			)
			(layer "F.SilkS")
		)
		(fp_line
			(start 1.651 1.778)
			(end 1.651 -1.778)
			(stroke
				(width 0.1524)
				(type default)
			)
			(layer "F.SilkS")
		)
		(fp_line
			(start -1.651 1.778)
			(end 1.651 1.778)
			(stroke
				(width 0.1524)
				(type default)
			)
			(layer "F.SilkS")
		)
		(fp_poly
			(pts
				(xy -1.778 1.8796) (xy -1.778 -1.8796) (xy 1.778 -1.8796) (xy 1.778 1.8796)
			)
			(stroke
				(width 0)
				(type default)
			)
			(fill no)
			(layer "F.CrtYd")
		)
		(fp_poly
			(pts
				(xy -1.778 1.8796) (xy -1.778 -1.8796) (xy 1.778 -1.8796) (xy 1.778 1.8796)
			)
			(stroke
				(width 0)
				(type default)
			)
			(fill no)
			(layer "F.Fab")
		)
		(pad "D" smd custom
			(at 0 -0.9525 90)
			(size 0.1905 0.1905)
			(layers "F.Cu" "F.Mask" "F.Paste")
			(net "ATTN_LED_DR14_MOS_N")
			(options
				(clearance outline)
				(anchor circle)
			)
			(primitives
				(gr_poly
					(pts
						(arc
							(start -0.1778 0.5715)
							(mid -0.321484 0.511984)
							(end -0.381 0.3683)
						)
						(arc
							(start -0.381 -0.3683)
							(mid -0.321484 -0.511984)
							(end -0.1778 -0.5715)
						)
						(arc
							(start 0.1778 -0.5715)
							(mid 0.321484 -0.511984)
							(end 0.381 -0.3683)
						)
						(arc
							(start 0.381 0.3683)
							(mid 0.321484 0.511984)
							(end 0.1778 0.5715)
						)
					)
					(width 0)
					(fill yes)
				)
			)
		)
		(pad "G" smd custom
			(at -0.98425 0.9525 90)
			(size 0.1905 0.1905)
			(layers "F.Cu" "F.Mask" "F.Paste")
			(net "SSD14_CLK0_OE_MOS_N")
			(options
				(clearance outline)
				(anchor circle)
			)
			(primitives
				(gr_poly
					(pts
						(arc
							(start -0.1778 0.5715)
							(mid -0.321484 0.511984)
							(end -0.381 0.3683)
						)
						(arc
							(start -0.381 -0.3683)
							(mid -0.321484 -0.511984)
							(end -0.1778 -0.5715)
						)
						(arc
							(start 0.1778 -0.5715)
							(mid 0.321484 -0.511984)
							(end 0.381 -0.3683)
						)
						(arc
							(start 0.381 0.3683)
							(mid 0.321484 0.511984)
							(end 0.1778 0.5715)
						)
					)
					(width 0)
					(fill yes)
				)
			)
		)
		(pad "S" smd custom
			(at 0.98425 0.9525 90)
			(size 0.1905 0.1905)
			(layers "F.Cu" "F.Mask" "F.Paste")
			(net "ATTN_LED_DR14_R")
			(options
				(clearance outline)
				(anchor circle)
			)
			(primitives
				(gr_poly
					(pts
						(arc
							(start -0.1778 0.5715)
							(mid -0.321484 0.511984)
							(end -0.381 0.3683)
						)
						(arc
							(start -0.381 -0.3683)
							(mid -0.321484 -0.511984)
							(end -0.1778 -0.5715)
						)
						(arc
							(start 0.1778 -0.5715)
							(mid 0.321484 -0.511984)
							(end 0.381 -0.3683)
						)
						(arc
							(start 0.381 0.3683)
							(mid 0.321484 0.511984)
							(end 0.1778 0.5715)
						)
					)
					(width 0)
					(fill yes)
				)
			)
		)
	)
	(footprint ""
		(layer "F.Cu")
		(at 224.623122 -424.443398 -90)
		(property "Reference" "PC1276"
			(at 0 0 270)
			(layer "F.SilkS")
			(hide yes)
			(effects
				(font
					(size 1.27 1.27)
				)
			)
		)
		(property "Value" "SC22U25V6KX-GP-U"
			(at -2.860802 -5.279644 270)
			(unlocked yes)
			(layer "F.Fab")
			(hide yes)
			(effects
				(font
					(size 1.016 1.016)
					(thickness 0.1524)
				)
			)
		)
		(property "Device Type" "C1206-TO0D3H75"
			(at -2.860802 -6.803644 270)
			(unlocked yes)
			(layer "F.Fab")
			(hide yes)
			(effects
				(font
					(size 1.016 1.016)
					(thickness 0.1524)
				)
			)
		)
		(duplicate_pad_numbers_are_jumpers no)
		(fp_line
			(start -1.3081 2.3749)
			(end -1.3081 -2.3749)
			(stroke
				(width 0.1524)
				(type default)
			)
			(layer "F.SilkS")
		)
		(fp_line
			(start 1.3081 2.3749)
			(end -1.3081 2.3749)
			(stroke
				(width 0.1524)
				(type default)
			)
			(layer "F.SilkS")
		)
		(fp_line
			(start -1.3081 -2.3749)
			(end 1.3081 -2.3749)
			(stroke
				(width 0.1524)
				(type default)
			)
			(layer "F.SilkS")
		)
		(fp_line
			(start 1.3081 -2.3749)
			(end 1.3081 2.3749)
			(stroke
				(width 0.1524)
				(type default)
			)
			(layer "F.SilkS")
		)
		(fp_rect
			(start -0.8001 1.6002)
			(end 0.8001 -1.6002)
			(stroke
				(width 0)
				(type default)
			)
			(fill no)
			(layer "F.CrtYd")
		)
		(fp_poly
			(pts
				(xy -1.5621 2.4511) (xy -1.5621 1.6002) (xy 0.8001 1.6002) (xy 0.8001 -1.6002) (xy -0.8001 -1.6002)
				(xy -0.8001 1.5875) (xy -1.5621 1.5875) (xy -1.5621 -2.4511) (xy 1.5621 -2.4511) (xy 1.5621 2.4511)
			)
			(stroke
				(width 0)
				(type default)
			)
			(fill no)
			(layer "F.CrtYd")
		)
		(fp_rect
			(start -1.5621 2.4511)
			(end 1.5621 -2.4511)
			(stroke
				(width 0)
				(type default)
			)
			(fill no)
			(layer "F.Fab")
		)
		(pad "1" smd rect
			(at 0 -1.392936 270)
			(size 2.1082 1.4478)
			(layers "F.Cu" "F.Mask" "F.Paste")
			(net "P3V3_VIN")
		)
		(pad "2" smd rect
			(at 0 1.392936 270)
			(size 2.1082 1.4478)
			(layers "F.Cu" "F.Mask" "F.Paste")
			(net "GND")
		)
	)
)
